(kicad_pcb
	(version 20260206)
	(generator "pcbnew")
	(generator_version "10.0")
	(general
		(thickness 1.6)
		(legacy_teardrops no)
	)
	(paper "A4")
	(title_block
		(title "04192023_DAF0TMB3IC0_F0TG_MB_C_brd_V02_OCP.brd")
		(comment 1 "Grand Teton / footprints 4655-4660 of 8354")
	)
	(layers
		(0 "F.Cu" signal "TOP")
		(4 "In1.Cu" signal "GND")
		(6 "In2.Cu" signal "IN1")
		(8 "In3.Cu" signal "GND1")
		(10 "In4.Cu" signal "IN2")
		(12 "In5.Cu" signal "GND2")
		(14 "In6.Cu" signal "IN3")
		(16 "In7.Cu" signal "GND3")
		(18 "In8.Cu" signal "VCC")
		(20 "In9.Cu" signal "VCC1")
		(22 "In10.Cu" signal "GND4")
		(24 "In11.Cu" signal "IN4")
		(26 "In12.Cu" signal "GND5")
		(28 "In13.Cu" signal "IN5")
		(30 "In14.Cu" signal "GND6")
		(32 "In15.Cu" signal "IN6")
		(34 "In16.Cu" signal "GND7")
		(2 "B.Cu" signal "BOTTOM")
		(9 "F.Adhes" user "F.Adhesive")
		(11 "B.Adhes" user "B.Adhesive")
		(13 "F.Paste" user "Package Geometry/Pastemask Top")
		(15 "B.Paste" user "Package Geometry/Pastemask Bottom")
		(5 "F.SilkS" user "Ref Des/Silkscreen Top")
		(7 "B.SilkS" user "Ref Des/Silkscreen Bottom")
		(1 "F.Mask" user "Board Geometry/Soldermask Top")
		(3 "B.Mask" user "Board Geometry/Soldermask Bottom")
		(17 "Dwgs.User" user "User.Drawings")
		(19 "Cmts.User" user "User.Comments")
		(21 "Eco1.User" user "User.Eco1")
		(23 "Eco2.User" user "User.Eco2")
		(25 "Edge.Cuts" user "Board Geometry/Outline")
		(27 "Margin" user)
		(31 "F.CrtYd" user "Package Geometry/Place Bound Top")
		(29 "B.CrtYd" user "Package Geometry/Place Bound Bottom")
		(35 "F.Fab" user "Ref Des/Assembly Top")
		(33 "B.Fab" user "Ref Des/Assembly Bottom")
	)
	(footprint ""
		(layer "F.Cu")
		(at 334.731614 -144.055592 180)
		(property "Reference" "PC237"
			(at 0 0 180)
			(layer "F.SilkS")
			(hide yes)
			(effects
				(font
					(size 1.27 1.27)
				)
			)
		)
		(property "Value" ""
			(at 0 0 180)
			(layer "F.Fab")
			(effects
				(font
					(size 1.27 1.27)
				)
			)
		)
		(duplicate_pad_numbers_are_jumpers no)
		(fp_line
			(start 0.7874 0.4064)
			(end -0.7874 0.4064)
			(stroke
				(width 0.1524)
				(type default)
			)
			(layer "F.SilkS")
		)
		(fp_line
			(start 0.7874 -0.4064)
			(end 0.7874 0.4064)
			(stroke
				(width 0.1524)
				(type default)
			)
			(layer "F.SilkS")
		)
		(fp_line
			(start -0.7874 0.4064)
			(end -0.7874 -0.4064)
			(stroke
				(width 0.1524)
				(type default)
			)
			(layer "F.SilkS")
		)
		(fp_line
			(start -0.7874 -0.4064)
			(end 0.7874 -0.4064)
			(stroke
				(width 0.1524)
				(type default)
			)
			(layer "F.SilkS")
		)
		(fp_line
			(start 0.67945 0.3048)
			(end 0.120396 0.3048)
			(stroke
				(width 0.1)
				(type default)
			)
			(layer "F.Fab")
		)
		(fp_line
			(start 0.67945 -0.3048)
			(end 0.67945 0.3048)
			(stroke
				(width 0.1)
				(type default)
			)
			(layer "F.Fab")
		)
		(fp_line
			(start 0.12065 -0.2794)
			(end 0.12065 -0.3048)
			(stroke
				(width 0.1)
				(type default)
			)
			(layer "F.Fab")
		)
		(fp_line
			(start 0.12065 -0.3048)
			(end 0.67945 -0.3048)
			(stroke
				(width 0.1)
				(type default)
			)
			(layer "F.Fab")
		)
		(fp_line
			(start 0.120396 0.3048)
			(end 0.120396 0.2794)
			(stroke
				(width 0.1)
				(type default)
			)
			(layer "F.Fab")
		)
		(fp_line
			(start 0.120396 0.2794)
			(end -0.12065 0.2794)
			(stroke
				(width 0.1)
				(type default)
			)
			(layer "F.Fab")
		)
		(fp_line
			(start -0.12065 0.3048)
			(end -0.67945 0.3048)
			(stroke
				(width 0.1)
				(type default)
			)
			(layer "F.Fab")
		)
		(fp_line
			(start -0.12065 0.2794)
			(end -0.12065 0.3048)
			(stroke
				(width 0.1)
				(type default)
			)
			(layer "F.Fab")
		)
		(fp_line
			(start -0.12065 -0.2794)
			(end 0.12065 -0.2794)
			(stroke
				(width 0.1)
				(type default)
			)
			(layer "F.Fab")
		)
		(fp_line
			(start -0.12065 -0.305054)
			(end -0.12065 -0.2794)
			(stroke
				(width 0.1)
				(type default)
			)
			(layer "F.Fab")
		)
		(fp_line
			(start -0.67945 0.3048)
			(end -0.67945 -0.305054)
			(stroke
				(width 0.1)
				(type default)
			)
			(layer "F.Fab")
		)
		(fp_line
			(start -0.67945 -0.305054)
			(end -0.12065 -0.305054)
			(stroke
				(width 0.1)
				(type default)
			)
			(layer "F.Fab")
		)
		(pad "1" smd circle
			(at -0.40005 0 180)
			(size 0 0)
			(layers "F.Cu" "F.Mask" "F.Paste")
			(net "SW_P12V_AUX_PVDD18_S5_P0_FLT")
		)
		(pad "2" smd circle
			(at 0.40005 0 180)
			(size 0 0)
			(layers "F.Cu" "F.Mask" "F.Paste")
			(net "GND")
		)
	)
	(footprint ""
		(layer "F.Cu")
		(at 443.982602 -418.17671 -90)
		(property "Reference" "PR6609"
			(at 0 0 270)
			(layer "F.SilkS")
			(hide yes)
			(effects
				(font
					(size 1.27 1.27)
				)
			)
		)
		(property "Value" ""
			(at 0 0 270)
			(layer "F.Fab")
			(effects
				(font
					(size 1.27 1.27)
				)
			)
		)
		(duplicate_pad_numbers_are_jumpers no)
		(fp_line
			(start -0.7874 0.4064)
			(end -0.7874 -0.4064)
			(stroke
				(width 0.1524)
				(type default)
			)
			(layer "F.SilkS")
		)
		(fp_line
			(start 0.7874 0.4064)
			(end -0.7874 0.4064)
			(stroke
				(width 0.1524)
				(type default)
			)
			(layer "F.SilkS")
		)
		(fp_line
			(start -0.7874 -0.4064)
			(end 0.7874 -0.4064)
			(stroke
				(width 0.1524)
				(type default)
			)
			(layer "F.SilkS")
		)
		(fp_line
			(start 0.7874 -0.4064)
			(end 0.7874 0.4064)
			(stroke
				(width 0.1524)
				(type default)
			)
			(layer "F.SilkS")
		)
		(fp_line
			(start -0.67945 0.3048)
			(end -0.67945 -0.305054)
			(stroke
				(width 0.1)
				(type default)
			)
			(layer "F.Fab")
		)
		(fp_line
			(start -0.12065 0.3048)
			(end -0.67945 0.3048)
			(stroke
				(width 0.1)
				(type default)
			)
			(layer "F.Fab")
		)
		(fp_line
			(start 0.120396 0.3048)
			(end 0.120396 0.2794)
			(stroke
				(width 0.1)
				(type default)
			)
			(layer "F.Fab")
		)
		(fp_line
			(start 0.67945 0.3048)
			(end 0.120396 0.3048)
			(stroke
				(width 0.1)
				(type default)
			)
			(layer "F.Fab")
		)
		(fp_line
			(start -0.12065 0.2794)
			(end -0.12065 0.3048)
			(stroke
				(width 0.1)
				(type default)
			)
			(layer "F.Fab")
		)
		(fp_line
			(start 0.120396 0.2794)
			(end -0.12065 0.2794)
			(stroke
				(width 0.1)
				(type default)
			)
			(layer "F.Fab")
		)
		(fp_line
			(start -0.12065 -0.2794)
			(end 0.12065 -0.2794)
			(stroke
				(width 0.1)
				(type default)
			)
			(layer "F.Fab")
		)
		(fp_line
			(start 0.12065 -0.2794)
			(end 0.12065 -0.3048)
			(stroke
				(width 0.1)
				(type default)
			)
			(layer "F.Fab")
		)
		(fp_line
			(start 0.12065 -0.3048)
			(end 0.67945 -0.3048)
			(stroke
				(width 0.1)
				(type default)
			)
			(layer "F.Fab")
		)
		(fp_line
			(start 0.67945 -0.3048)
			(end 0.67945 0.3048)
			(stroke
				(width 0.1)
				(type default)
			)
			(layer "F.Fab")
		)
		(fp_line
			(start -0.67945 -0.305054)
			(end -0.12065 -0.305054)
			(stroke
				(width 0.1)
				(type default)
			)
			(layer "F.Fab")
		)
		(fp_line
			(start -0.12065 -0.305054)
			(end -0.12065 -0.2794)
			(stroke
				(width 0.1)
				(type default)
			)
			(layer "F.Fab")
		)
		(pad "1" smd circle
			(at -0.40005 0 270)
			(size 0 0)
			(layers "F.Cu" "F.Mask" "F.Paste")
			(net "NC_P0V9_RETIMER_CPU0_IMON3")
		)
		(pad "2" smd circle
			(at 0.40005 0 270)
			(size 0 0)
			(layers "F.Cu" "F.Mask" "F.Paste")
			(net "GND")
		)
	)
	(footprint ""
		(layer "F.Cu")
		(at 94.478348 -136.059418 90)
		(property "Reference" "R149"
			(at 0 0 90)
			(layer "F.SilkS")
			(hide yes)
			(effects
				(font
					(size 1.27 1.27)
				)
			)
		)
		(property "Value" ""
			(at 0 0 90)
			(layer "F.Fab")
			(effects
				(font
					(size 1.27 1.27)
				)
			)
		)
		(duplicate_pad_numbers_are_jumpers no)
		(fp_line
			(start 0.7874 -0.4064)
			(end 0.7874 0.4064)
			(stroke
				(width 0.1524)
				(type default)
			)
			(layer "F.SilkS")
		)
		(fp_line
			(start -0.7874 -0.4064)
			(end 0.7874 -0.4064)
			(stroke
				(width 0.1524)
				(type default)
			)
			(layer "F.SilkS")
		)
		(fp_line
			(start 0.7874 0.4064)
			(end -0.7874 0.4064)
			(stroke
				(width 0.1524)
				(type default)
			)
			(layer "F.SilkS")
		)
		(fp_line
			(start -0.7874 0.4064)
			(end -0.7874 -0.4064)
			(stroke
				(width 0.1524)
				(type default)
			)
			(layer "F.SilkS")
		)
		(fp_line
			(start -0.12065 -0.305054)
			(end -0.12065 -0.2794)
			(stroke
				(width 0.1)
				(type default)
			)
			(layer "F.Fab")
		)
		(fp_line
			(start -0.67945 -0.305054)
			(end -0.12065 -0.305054)
			(stroke
				(width 0.1)
				(type default)
			)
			(layer "F.Fab")
		)
		(fp_line
			(start 0.67945 -0.3048)
			(end 0.67945 0.3048)
			(stroke
				(width 0.1)
				(type default)
			)
			(layer "F.Fab")
		)
		(fp_line
			(start 0.12065 -0.3048)
			(end 0.67945 -0.3048)
			(stroke
				(width 0.1)
				(type default)
			)
			(layer "F.Fab")
		)
		(fp_line
			(start 0.12065 -0.2794)
			(end 0.12065 -0.3048)
			(stroke
				(width 0.1)
				(type default)
			)
			(layer "F.Fab")
		)
		(fp_line
			(start -0.12065 -0.2794)
			(end 0.12065 -0.2794)
			(stroke
				(width 0.1)
				(type default)
			)
			(layer "F.Fab")
		)
		(fp_line
			(start 0.120396 0.2794)
			(end -0.12065 0.2794)
			(stroke
				(width 0.1)
				(type default)
			)
			(layer "F.Fab")
		)
		(fp_line
			(start -0.12065 0.2794)
			(end -0.12065 0.3048)
			(stroke
				(width 0.1)
				(type default)
			)
			(layer "F.Fab")
		)
		(fp_line
			(start 0.67945 0.3048)
			(end 0.120396 0.3048)
			(stroke
				(width 0.1)
				(type default)
			)
			(layer "F.Fab")
		)
		(fp_line
			(start 0.120396 0.3048)
			(end 0.120396 0.2794)
			(stroke
				(width 0.1)
				(type default)
			)
			(layer "F.Fab")
		)
		(fp_line
			(start -0.12065 0.3048)
			(end -0.67945 0.3048)
			(stroke
				(width 0.1)
				(type default)
			)
			(layer "F.Fab")
		)
		(fp_line
			(start -0.67945 0.3048)
			(end -0.67945 -0.305054)
			(stroke
				(width 0.1)
				(type default)
			)
			(layer "F.Fab")
		)
		(pad "1" smd circle
			(at -0.40005 0 90)
			(size 0 0)
			(layers "F.Cu" "F.Mask" "F.Paste")
			(net "PVDDCR_SOC_P1_EN")
		)
		(pad "2" smd circle
			(at 0.40005 0 90)
			(size 0 0)
			(layers "F.Cu" "F.Mask" "F.Paste")
			(net "PVDDCR_SOC_P1_EN_RC")
		)
	)
	(footprint ""
		(layer "F.Cu")
		(at 355.617272 -261.747762 -90)
		(property "Reference" "C2150"
			(at 0 0 270)
			(layer "F.SilkS")
			(hide yes)
			(effects
				(font
					(size 1.27 1.27)
				)
			)
		)
		(property "Value" ""
			(at 0 0 270)
			(layer "F.Fab")
			(effects
				(font
					(size 1.27 1.27)
				)
			)
		)
		(duplicate_pad_numbers_are_jumpers no)
		(fp_line
			(start -0.7874 0.4064)
			(end -0.7874 -0.4064)
			(stroke
				(width 0.1524)
				(type default)
			)
			(layer "F.SilkS")
		)
		(fp_line
			(start 0.7874 0.4064)
			(end -0.7874 0.4064)
			(stroke
				(width 0.1524)
				(type default)
			)
			(layer "F.SilkS")
		)
		(fp_line
			(start -0.7874 -0.4064)
			(end 0.7874 -0.4064)
			(stroke
				(width 0.1524)
				(type default)
			)
			(layer "F.SilkS")
		)
		(fp_line
			(start 0.7874 -0.4064)
			(end 0.7874 0.4064)
			(stroke
				(width 0.1524)
				(type default)
			)
			(layer "F.SilkS")
		)
		(fp_line
			(start -0.67945 0.3048)
			(end -0.67945 -0.305054)
			(stroke
				(width 0.1)
				(type default)
			)
			(layer "F.Fab")
		)
		(fp_line
			(start -0.12065 0.3048)
			(end -0.67945 0.3048)
			(stroke
				(width 0.1)
				(type default)
			)
			(layer "F.Fab")
		)
		(fp_line
			(start 0.120396 0.3048)
			(end 0.120396 0.2794)
			(stroke
				(width 0.1)
				(type default)
			)
			(layer "F.Fab")
		)
		(fp_line
			(start 0.67945 0.3048)
			(end 0.120396 0.3048)
			(stroke
				(width 0.1)
				(type default)
			)
			(layer "F.Fab")
		)
		(fp_line
			(start -0.12065 0.2794)
			(end -0.12065 0.3048)
			(stroke
				(width 0.1)
				(type default)
			)
			(layer "F.Fab")
		)
		(fp_line
			(start 0.120396 0.2794)
			(end -0.12065 0.2794)
			(stroke
				(width 0.1)
				(type default)
			)
			(layer "F.Fab")
		)
		(fp_line
			(start -0.12065 -0.2794)
			(end 0.12065 -0.2794)
			(stroke
				(width 0.1)
				(type default)
			)
			(layer "F.Fab")
		)
		(fp_line
			(start 0.12065 -0.2794)
			(end 0.12065 -0.3048)
			(stroke
				(width 0.1)
				(type default)
			)
			(layer "F.Fab")
		)
		(fp_line
			(start 0.12065 -0.3048)
			(end 0.67945 -0.3048)
			(stroke
				(width 0.1)
				(type default)
			)
			(layer "F.Fab")
		)
		(fp_line
			(start 0.67945 -0.3048)
			(end 0.67945 0.3048)
			(stroke
				(width 0.1)
				(type default)
			)
			(layer "F.Fab")
		)
		(fp_line
			(start -0.67945 -0.305054)
			(end -0.12065 -0.305054)
			(stroke
				(width 0.1)
				(type default)
			)
			(layer "F.Fab")
		)
		(fp_line
			(start -0.12065 -0.305054)
			(end -0.12065 -0.2794)
			(stroke
				(width 0.1)
				(type default)
			)
			(layer "F.Fab")
		)
		(pad "1" smd circle
			(at -0.40005 0 270)
			(size 0 0)
			(layers "F.Cu" "F.Mask" "F.Paste")
			(net "PVDD11_S3_P0")
		)
		(pad "2" smd circle
			(at 0.40005 0 270)
			(size 0 0)
			(layers "F.Cu" "F.Mask" "F.Paste")
			(net "GND")
		)
	)
	(footprint ""
		(layer "F.Cu")
		(at 352.05543 -431.809652 180)
		(property "Reference" "R4550"
			(at 0 0 180)
			(layer "F.SilkS")
			(hide yes)
			(effects
				(font
					(size 1.27 1.27)
				)
			)
		)
		(property "Value" ""
			(at 0 0 180)
			(layer "F.Fab")
			(effects
				(font
					(size 1.27 1.27)
				)
			)
		)
		(duplicate_pad_numbers_are_jumpers no)
		(fp_line
			(start 0.7874 0.4064)
			(end -0.7874 0.4064)
			(stroke
				(width 0.1524)
				(type default)
			)
			(layer "F.SilkS")
		)
		(fp_line
			(start 0.7874 -0.4064)
			(end 0.7874 0.4064)
			(stroke
				(width 0.1524)
				(type default)
			)
			(layer "F.SilkS")
		)
		(fp_line
			(start -0.7874 0.4064)
			(end -0.7874 -0.4064)
			(stroke
				(width 0.1524)
				(type default)
			)
			(layer "F.SilkS")
		)
		(fp_line
			(start -0.7874 -0.4064)
			(end 0.7874 -0.4064)
			(stroke
				(width 0.1524)
				(type default)
			)
			(layer "F.SilkS")
		)
		(fp_line
			(start 0.67945 0.3048)
			(end 0.120396 0.3048)
			(stroke
				(width 0.1)
				(type default)
			)
			(layer "F.Fab")
		)
		(fp_line
			(start 0.67945 -0.3048)
			(end 0.67945 0.3048)
			(stroke
				(width 0.1)
				(type default)
			)
			(layer "F.Fab")
		)
		(fp_line
			(start 0.12065 -0.2794)
			(end 0.12065 -0.3048)
			(stroke
				(width 0.1)
				(type default)
			)
			(layer "F.Fab")
		)
		(fp_line
			(start 0.12065 -0.3048)
			(end 0.67945 -0.3048)
			(stroke
				(width 0.1)
				(type default)
			)
			(layer "F.Fab")
		)
		(fp_line
			(start 0.120396 0.3048)
			(end 0.120396 0.2794)
			(stroke
				(width 0.1)
				(type default)
			)
			(layer "F.Fab")
		)
		(fp_line
			(start 0.120396 0.2794)
			(end -0.12065 0.2794)
			(stroke
				(width 0.1)
				(type default)
			)
			(layer "F.Fab")
		)
		(fp_line
			(start -0.12065 0.3048)
			(end -0.67945 0.3048)
			(stroke
				(width 0.1)
				(type default)
			)
			(layer "F.Fab")
		)
		(fp_line
			(start -0.12065 0.2794)
			(end -0.12065 0.3048)
			(stroke
				(width 0.1)
				(type default)
			)
			(layer "F.Fab")
		)
		(fp_line
			(start -0.12065 -0.2794)
			(end 0.12065 -0.2794)
			(stroke
				(width 0.1)
				(type default)
			)
			(layer "F.Fab")
		)
		(fp_line
			(start -0.12065 -0.305054)
			(end -0.12065 -0.2794)
			(stroke
				(width 0.1)
				(type default)
			)
			(layer "F.Fab")
		)
		(fp_line
			(start -0.67945 0.3048)
			(end -0.67945 -0.305054)
			(stroke
				(width 0.1)
				(type default)
			)
			(layer "F.Fab")
		)
		(fp_line
			(start -0.67945 -0.305054)
			(end -0.12065 -0.305054)
			(stroke
				(width 0.1)
				(type default)
			)
			(layer "F.Fab")
		)
		(pad "1" smd circle
			(at -0.40005 0 180)
			(size 0 0)
			(layers "F.Cu" "F.Mask" "F.Paste")
			(net "SWB_HSC_EN_BUF_R")
		)
		(pad "2" smd circle
			(at 0.40005 0 180)
			(size 0 0)
			(layers "F.Cu" "F.Mask" "F.Paste")
			(net "SWB_HSC_EN_BUF")
		)
	)
	(footprint ""
		(layer "F.Cu")
		(at 409.46451 -136.835642 180)
		(property "Reference" "R2316"
			(at 0 0 180)
			(layer "F.SilkS")
			(hide yes)
			(effects
				(font
					(size 1.27 1.27)
				)
			)
		)
		(property "Value" ""
			(at 0 0 180)
			(layer "F.Fab")
			(effects
				(font
					(size 1.27 1.27)
				)
			)
		)
		(duplicate_pad_numbers_are_jumpers no)
		(fp_line
			(start 0.7874 0.4064)
			(end -0.7874 0.4064)
			(stroke
				(width 0.1524)
				(type default)
			)
			(layer "F.SilkS")
		)
		(fp_line
			(start 0.7874 -0.4064)
			(end 0.7874 0.4064)
			(stroke
				(width 0.1524)
				(type default)
			)
			(layer "F.SilkS")
		)
		(fp_line
			(start -0.7874 0.4064)
			(end -0.7874 -0.4064)
			(stroke
				(width 0.1524)
				(type default)
			)
			(layer "F.SilkS")
		)
		(fp_line
			(start -0.7874 -0.4064)
			(end 0.7874 -0.4064)
			(stroke
				(width 0.1524)
				(type default)
			)
			(layer "F.SilkS")
		)
		(fp_line
			(start 0.67945 0.3048)
			(end 0.120396 0.3048)
			(stroke
				(width 0.1)
				(type default)
			)
			(layer "F.Fab")
		)
		(fp_line
			(start 0.67945 -0.3048)
			(end 0.67945 0.3048)
			(stroke
				(width 0.1)
				(type default)
			)
			(layer "F.Fab")
		)
		(fp_line
			(start 0.12065 -0.2794)
			(end 0.12065 -0.3048)
			(stroke
				(width 0.1)
				(type default)
			)
			(layer "F.Fab")
		)
		(fp_line
			(start 0.12065 -0.3048)
			(end 0.67945 -0.3048)
			(stroke
				(width 0.1)
				(type default)
			)
			(layer "F.Fab")
		)
		(fp_line
			(start 0.120396 0.3048)
			(end 0.120396 0.2794)
			(stroke
				(width 0.1)
				(type default)
			)
			(layer "F.Fab")
		)
		(fp_line
			(start 0.120396 0.2794)
			(end -0.12065 0.2794)
			(stroke
				(width 0.1)
				(type default)
			)
			(layer "F.Fab")
		)
		(fp_line
			(start -0.12065 0.3048)
			(end -0.67945 0.3048)
			(stroke
				(width 0.1)
				(type default)
			)
			(layer "F.Fab")
		)
		(fp_line
			(start -0.12065 0.2794)
			(end -0.12065 0.3048)
			(stroke
				(width 0.1)
				(type default)
			)
			(layer "F.Fab")
		)
		(fp_line
			(start -0.12065 -0.2794)
			(end 0.12065 -0.2794)
			(stroke
				(width 0.1)
				(type default)
			)
			(layer "F.Fab")
		)
		(fp_line
			(start -0.12065 -0.305054)
			(end -0.12065 -0.2794)
			(stroke
				(width 0.1)
				(type default)
			)
			(layer "F.Fab")
		)
		(fp_line
			(start -0.67945 0.3048)
			(end -0.67945 -0.305054)
			(stroke
				(width 0.1)
				(type default)
			)
			(layer "F.Fab")
		)
		(fp_line
			(start -0.67945 -0.305054)
			(end -0.12065 -0.305054)
			(stroke
				(width 0.1)
				(type default)
			)
			(layer "F.Fab")
		)
		(pad "1" smd circle
			(at -0.40005 0 180)
			(size 0 0)
			(layers "F.Cu" "F.Mask" "F.Paste")
			(net "PWRGD_P5V_AUX_R")
		)
		(pad "2" smd circle
			(at 0.40005 0 180)
			(size 0 0)
			(layers "F.Cu" "F.Mask" "F.Paste")
			(net "PWRGD_P5V_AUX")
		)
	)
)
